(kicad_pcb
	(version 20260206)
	(generator "pcbnew")
	(generator_version "10.0")
	(general
		(thickness 1.6)
		(legacy_teardrops no)
	)
	(paper "A4")
	(title_block
		(title "panther-plus-userver — 13130-1b_20150205.brd")
		(comment 1 "Honey Badger (Wiwynn) / footprints 1417-1423 of 1509")
	)
	(layers
		(0 "F.Cu" signal "TOP")
		(4 "In1.Cu" signal "L2")
		(6 "In2.Cu" signal "L3")
		(8 "In3.Cu" signal "L4")
		(10 "In4.Cu" signal "L5")
		(12 "In5.Cu" signal "L6")
		(14 "In6.Cu" signal "L7")
		(16 "In7.Cu" signal "L8")
		(18 "In8.Cu" signal "L9")
		(20 "In9.Cu" signal "L10")
		(22 "In10.Cu" signal "L11")
		(2 "B.Cu" signal "BOTTOM")
		(9 "F.Adhes" user "F.Adhesive")
		(11 "B.Adhes" user "B.Adhesive")
		(13 "F.Paste" user "Package Geometry/Pastemask Top")
		(15 "B.Paste" user "Package Geometry/Pastemask Bottom")
		(5 "F.SilkS" user "Ref Des/Silkscreen Top")
		(7 "B.SilkS" user "Ref Des/Silkscreen Bottom")
		(1 "F.Mask" user "Board Geometry/Soldermask Top")
		(3 "B.Mask" user "Board Geometry/Soldermask Bottom")
		(17 "Dwgs.User" user "User.Drawings")
		(19 "Cmts.User" user "User.Comments")
		(21 "Eco1.User" user "User.Eco1")
		(23 "Eco2.User" user "User.Eco2")
		(25 "Edge.Cuts" user "Board Geometry/Outline")
		(27 "Margin" user)
		(31 "F.CrtYd" user "Package Geometry/Place Bound Top")
		(29 "B.CrtYd" user "Package Geometry/Place Bound Bottom")
		(35 "F.Fab" user "Ref Des/Assembly Top")
		(33 "B.Fab" user "Ref Des/Assembly Bottom")
	)
	(footprint ""
		(layer "B.Cu")
		(at 94.0562 -33.782)
		(property "Reference" "C217"
			(at 0 0 0)
			(layer "B.SilkS")
			(hide yes)
			(effects
				(font
					(size 1.27 1.27)
				)
				(justify mirror)
			)
		)
		(property "Value" "SC1U10V2KX-1GP"
			(at -1.1811 -2.7051 0)
			(unlocked yes)
			(layer "B.Fab")
			(hide yes)
			(effects
				(font
					(size 1.016 1.016)
					(thickness 0.1524)
				)
				(justify mirror)
			)
		)
		(property "Device Type" "C402H22"
			(at -1.1811 -4.2291 0)
			(unlocked yes)
			(layer "B.Fab")
			(hide yes)
			(effects
				(font
					(size 1.016 1.016)
					(thickness 0.1524)
				)
				(justify mirror)
			)
		)
		(duplicate_pad_numbers_are_jumpers no)
		(fp_rect
			(start 0.381 0.7366)
			(end -0.381 -0.7366)
			(stroke
				(width 0)
				(type default)
			)
			(fill no)
			(layer "B.CrtYd")
		)
		(fp_rect
			(start 0.381 0.7366)
			(end -0.381 -0.7366)
			(stroke
				(width 0)
				(type default)
			)
			(fill no)
			(layer "B.Fab")
		)
		(pad "1" smd custom
			(at 0 -0.4572 180)
			(size 0.1143 0.1143)
			(layers "B.Cu" "B.Mask" "B.Paste")
			(net "P1V0_STBY")
			(options
				(clearance outline)
				(anchor circle)
			)
			(primitives
				(gr_poly
					(pts
						(arc
							(start -0.254 0.1778)
							(mid -0.239121 0.213721)
							(end -0.2032 0.2286)
						)
						(arc
							(start 0.2032 0.2286)
							(mid 0.239121 0.213721)
							(end 0.254 0.1778)
						)
						(arc
							(start 0.254 -0.1778)
							(mid 0.239121 -0.213721)
							(end 0.2032 -0.2286)
						)
						(arc
							(start -0.2032 -0.2286)
							(mid -0.239121 -0.213721)
							(end -0.254 -0.1778)
						)
					)
					(width 0)
					(fill yes)
				)
			)
		)
		(pad "2" smd custom
			(at 0 0.4572 180)
			(size 0.1143 0.1143)
			(layers "B.Cu" "B.Mask" "B.Paste")
			(net "GND")
			(options
				(clearance outline)
				(anchor circle)
			)
			(primitives
				(gr_poly
					(pts
						(arc
							(start -0.254 0.1778)
							(mid -0.239121 0.213721)
							(end -0.2032 0.2286)
						)
						(arc
							(start 0.2032 0.2286)
							(mid 0.239121 0.213721)
							(end 0.254 0.1778)
						)
						(arc
							(start 0.254 -0.1778)
							(mid 0.239121 -0.213721)
							(end 0.2032 -0.2286)
						)
						(arc
							(start -0.2032 -0.2286)
							(mid -0.239121 -0.213721)
							(end -0.254 -0.1778)
						)
					)
					(width 0)
					(fill yes)
				)
			)
		)
	)
	(footprint ""
		(layer "B.Cu")
		(at 38.608 -42.672 90)
		(property "Reference" "C65"
			(at 0 0 90)
			(layer "B.SilkS")
			(hide yes)
			(effects
				(font
					(size 1.27 1.27)
				)
				(justify mirror)
			)
		)
		(property "Value" "SC27P50V2GN-GP"
			(at -1.8923 -1.2065 90)
			(unlocked yes)
			(layer "B.Fab")
			(hide yes)
			(effects
				(font
					(size 1.016 1.016)
					(thickness 0.1524)
				)
				(justify mirror)
			)
		)
		(property "Device Type" "C402H22"
			(at -1.8923 -2.7305 90)
			(unlocked yes)
			(layer "B.Fab")
			(hide yes)
			(effects
				(font
					(size 1.016 1.016)
					(thickness 0.1524)
				)
				(justify mirror)
			)
		)
		(duplicate_pad_numbers_are_jumpers no)
		(fp_rect
			(start 0.381 0.7366)
			(end -0.381 -0.7366)
			(stroke
				(width 0)
				(type default)
			)
			(fill no)
			(layer "B.CrtYd")
		)
		(fp_rect
			(start 0.381 0.7366)
			(end -0.381 -0.7366)
			(stroke
				(width 0)
				(type default)
			)
			(fill no)
			(layer "B.Fab")
		)
		(pad "1" smd custom
			(at 0 -0.4572 270)
			(size 0.1143 0.1143)
			(layers "B.Cu" "B.Mask" "B.Paste")
			(net "XTAL_CLK_GEN_OUT")
			(options
				(clearance outline)
				(anchor circle)
			)
			(primitives
				(gr_poly
					(pts
						(arc
							(start -0.254 0.1778)
							(mid -0.239121 0.213721)
							(end -0.2032 0.2286)
						)
						(arc
							(start 0.2032 0.2286)
							(mid 0.239121 0.213721)
							(end 0.254 0.1778)
						)
						(arc
							(start 0.254 -0.1778)
							(mid 0.239121 -0.213721)
							(end 0.2032 -0.2286)
						)
						(arc
							(start -0.2032 -0.2286)
							(mid -0.239121 -0.213721)
							(end -0.254 -0.1778)
						)
					)
					(width 0)
					(fill yes)
				)
			)
		)
		(pad "2" smd custom
			(at 0 0.4572 270)
			(size 0.1143 0.1143)
			(layers "B.Cu" "B.Mask" "B.Paste")
			(net "GND")
			(options
				(clearance outline)
				(anchor circle)
			)
			(primitives
				(gr_poly
					(pts
						(arc
							(start -0.254 0.1778)
							(mid -0.239121 0.213721)
							(end -0.2032 0.2286)
						)
						(arc
							(start 0.2032 0.2286)
							(mid 0.239121 0.213721)
							(end 0.254 0.1778)
						)
						(arc
							(start 0.254 -0.1778)
							(mid 0.239121 -0.213721)
							(end 0.2032 -0.2286)
						)
						(arc
							(start -0.2032 -0.2286)
							(mid -0.239121 -0.213721)
							(end -0.254 -0.1778)
						)
					)
					(width 0)
					(fill yes)
				)
			)
		)
	)
	(footprint ""
		(layer "B.Cu")
		(at 92.71 -45.6438 -90)
		(property "Reference" "C155"
			(at 0 0 90)
			(layer "B.SilkS")
			(hide yes)
			(effects
				(font
					(size 1.27 1.27)
				)
				(justify mirror)
			)
		)
		(property "Value" "SC1U10V2KX-1GP"
			(at -1.1811 -2.7051 270)
			(unlocked yes)
			(layer "B.Fab")
			(hide yes)
			(effects
				(font
					(size 1.016 1.016)
					(thickness 0.1524)
				)
				(justify mirror)
			)
		)
		(property "Device Type" "C402H22"
			(at -1.1811 -4.2291 270)
			(unlocked yes)
			(layer "B.Fab")
			(hide yes)
			(effects
				(font
					(size 1.016 1.016)
					(thickness 0.1524)
				)
				(justify mirror)
			)
		)
		(duplicate_pad_numbers_are_jumpers no)
		(fp_rect
			(start 0.381 0.7366)
			(end -0.381 -0.7366)
			(stroke
				(width 0)
				(type default)
			)
			(fill no)
			(layer "B.CrtYd")
		)
		(fp_rect
			(start 0.381 0.7366)
			(end -0.381 -0.7366)
			(stroke
				(width 0)
				(type default)
			)
			(fill no)
			(layer "B.Fab")
		)
		(pad "1" smd custom
			(at 0 -0.4572 90)
			(size 0.1143 0.1143)
			(layers "B.Cu" "B.Mask" "B.Paste")
			(net "P1V0")
			(options
				(clearance outline)
				(anchor circle)
			)
			(primitives
				(gr_poly
					(pts
						(arc
							(start -0.254 0.1778)
							(mid -0.239121 0.213721)
							(end -0.2032 0.2286)
						)
						(arc
							(start 0.2032 0.2286)
							(mid 0.239121 0.213721)
							(end 0.254 0.1778)
						)
						(arc
							(start 0.254 -0.1778)
							(mid 0.239121 -0.213721)
							(end 0.2032 -0.2286)
						)
						(arc
							(start -0.2032 -0.2286)
							(mid -0.239121 -0.213721)
							(end -0.254 -0.1778)
						)
					)
					(width 0)
					(fill yes)
				)
			)
		)
		(pad "2" smd custom
			(at 0 0.4572 90)
			(size 0.1143 0.1143)
			(layers "B.Cu" "B.Mask" "B.Paste")
			(net "GND")
			(options
				(clearance outline)
				(anchor circle)
			)
			(primitives
				(gr_poly
					(pts
						(arc
							(start -0.254 0.1778)
							(mid -0.239121 0.213721)
							(end -0.2032 0.2286)
						)
						(arc
							(start 0.2032 0.2286)
							(mid 0.239121 0.213721)
							(end 0.254 0.1778)
						)
						(arc
							(start 0.254 -0.1778)
							(mid 0.239121 -0.213721)
							(end 0.2032 -0.2286)
						)
						(arc
							(start -0.2032 -0.2286)
							(mid -0.239121 -0.213721)
							(end -0.254 -0.1778)
						)
					)
					(width 0)
					(fill yes)
				)
			)
		)
	)
	(footprint ""
		(layer "B.Cu")
		(at 197.993 -42.672 -90)
		(property "Reference" "R155"
			(at 0 0 90)
			(layer "B.SilkS")
			(hide yes)
			(effects
				(font
					(size 1.27 1.27)
				)
				(justify mirror)
			)
		)
		(property "Value" "300R2F-GP"
			(at -0.064008 -3.993896 270)
			(unlocked yes)
			(layer "B.Fab")
			(hide yes)
			(effects
				(font
					(size 1.016 1.016)
					(thickness 0.1524)
				)
				(justify mirror)
			)
		)
		(property "Device Type" "R402H16"
			(at -0.064008 -5.517896 270)
			(unlocked yes)
			(layer "B.Fab")
			(hide yes)
			(effects
				(font
					(size 1.016 1.016)
					(thickness 0.1524)
				)
				(justify mirror)
			)
		)
		(duplicate_pad_numbers_are_jumpers no)
		(fp_rect
			(start 0.381 0.8382)
			(end -0.381 -0.8382)
			(stroke
				(width 0)
				(type default)
			)
			(fill no)
			(layer "B.CrtYd")
		)
		(fp_rect
			(start 0.381 0.8382)
			(end -0.381 -0.8382)
			(stroke
				(width 0)
				(type default)
			)
			(fill no)
			(layer "B.Fab")
		)
		(pad "1" smd custom
			(at 0 -0.4318 90)
			(size 0.127 0.127)
			(layers "B.Cu" "B.Mask" "B.Paste")
			(net "PORT80_R_BIT6")
			(options
				(clearance outline)
				(anchor circle)
			)
			(primitives
				(gr_poly
					(pts
						(arc
							(start -0.2032 0.2794)
							(mid -0.239121 0.264521)
							(end -0.254 0.2286)
						)
						(arc
							(start -0.254 -0.2286)
							(mid -0.239121 -0.264521)
							(end -0.2032 -0.2794)
						)
						(arc
							(start 0.2032 -0.2794)
							(mid 0.239121 -0.264521)
							(end 0.254 -0.2286)
						)
						(arc
							(start 0.254 0.2286)
							(mid 0.239121 0.264521)
							(end 0.2032 0.2794)
						)
					)
					(width 0)
					(fill yes)
				)
			)
		)
		(pad "2" smd custom
			(at 0 0.4318 90)
			(size 0.127 0.127)
			(layers "B.Cu" "B.Mask" "B.Paste")
			(net "P3V3_STBY")
			(options
				(clearance outline)
				(anchor circle)
			)
			(primitives
				(gr_poly
					(pts
						(arc
							(start -0.2032 0.2794)
							(mid -0.239121 0.264521)
							(end -0.254 0.2286)
						)
						(arc
							(start -0.254 -0.2286)
							(mid -0.239121 -0.264521)
							(end -0.2032 -0.2794)
						)
						(arc
							(start 0.2032 -0.2794)
							(mid 0.239121 -0.264521)
							(end 0.254 -0.2286)
						)
						(arc
							(start 0.254 0.2286)
							(mid 0.239121 0.264521)
							(end 0.2032 0.2794)
						)
					)
					(width 0)
					(fill yes)
				)
			)
		)
	)
	(footprint ""
		(layer "B.Cu")
		(at 197.612 -4.6736 180)
		(property "Reference" "R384"
			(at 0 0 0)
			(layer "B.SilkS")
			(hide yes)
			(effects
				(font
					(size 1.27 1.27)
				)
				(justify mirror)
			)
		)
		(property "Value" "0R2J-2-GP"
			(at -0.064008 -3.993896 180)
			(unlocked yes)
			(layer "B.Fab")
			(hide yes)
			(effects
				(font
					(size 1.016 1.016)
					(thickness 0.1524)
				)
				(justify mirror)
			)
		)
		(property "Device Type" "R402H16"
			(at -0.064008 -5.517896 180)
			(unlocked yes)
			(layer "B.Fab")
			(hide yes)
			(effects
				(font
					(size 1.016 1.016)
					(thickness 0.1524)
				)
				(justify mirror)
			)
		)
		(duplicate_pad_numbers_are_jumpers no)
		(fp_rect
			(start 0.381 0.8382)
			(end -0.381 -0.8382)
			(stroke
				(width 0)
				(type default)
			)
			(fill no)
			(layer "B.CrtYd")
		)
		(fp_rect
			(start 0.381 0.8382)
			(end -0.381 -0.8382)
			(stroke
				(width 0)
				(type default)
			)
			(fill no)
			(layer "B.Fab")
		)
		(pad "1" smd custom
			(at 0 -0.4318)
			(size 0.127 0.127)
			(layers "B.Cu" "B.Mask" "B.Paste")
			(net "SMB_M_B0_R_DATA")
			(options
				(clearance outline)
				(anchor circle)
			)
			(primitives
				(gr_poly
					(pts
						(arc
							(start -0.2032 0.2794)
							(mid -0.239121 0.264521)
							(end -0.254 0.2286)
						)
						(arc
							(start -0.254 -0.2286)
							(mid -0.239121 -0.264521)
							(end -0.2032 -0.2794)
						)
						(arc
							(start 0.2032 -0.2794)
							(mid 0.239121 -0.264521)
							(end 0.254 -0.2286)
						)
						(arc
							(start 0.254 0.2286)
							(mid 0.239121 0.264521)
							(end 0.2032 0.2794)
						)
					)
					(width 0)
					(fill yes)
				)
			)
		)
		(pad "2" smd custom
			(at 0 0.4318)
			(size 0.127 0.127)
			(layers "B.Cu" "B.Mask" "B.Paste")
			(net "SMB_HOST_LV_DATA")
			(options
				(clearance outline)
				(anchor circle)
			)
			(primitives
				(gr_poly
					(pts
						(arc
							(start -0.2032 0.2794)
							(mid -0.239121 0.264521)
							(end -0.254 0.2286)
						)
						(arc
							(start -0.254 -0.2286)
							(mid -0.239121 -0.264521)
							(end -0.2032 -0.2794)
						)
						(arc
							(start 0.2032 -0.2794)
							(mid 0.239121 -0.264521)
							(end 0.254 -0.2286)
						)
						(arc
							(start 0.254 0.2286)
							(mid 0.239121 0.264521)
							(end 0.2032 0.2794)
						)
					)
					(width 0)
					(fill yes)
				)
			)
		)
	)
	(footprint ""
		(layer "B.Cu")
		(at 95.60306 -48.0441 180)
		(property "Reference" "C145"
			(at 0 0 0)
			(layer "B.SilkS")
			(hide yes)
			(effects
				(font
					(size 1.27 1.27)
				)
				(justify mirror)
			)
		)
		(property "Value" "SC1U10V2KX-1GP"
			(at -1.1811 -2.7051 180)
			(unlocked yes)
			(layer "B.Fab")
			(hide yes)
			(effects
				(font
					(size 1.016 1.016)
					(thickness 0.1524)
				)
				(justify mirror)
			)
		)
		(property "Device Type" "C402H22"
			(at -1.1811 -4.2291 180)
			(unlocked yes)
			(layer "B.Fab")
			(hide yes)
			(effects
				(font
					(size 1.016 1.016)
					(thickness 0.1524)
				)
				(justify mirror)
			)
		)
		(duplicate_pad_numbers_are_jumpers no)
		(fp_rect
			(start 0.381 0.7366)
			(end -0.381 -0.7366)
			(stroke
				(width 0)
				(type default)
			)
			(fill no)
			(layer "B.CrtYd")
		)
		(fp_rect
			(start 0.381 0.7366)
			(end -0.381 -0.7366)
			(stroke
				(width 0)
				(type default)
			)
			(fill no)
			(layer "B.Fab")
		)
		(pad "1" smd custom
			(at 0 -0.4572)
			(size 0.1143 0.1143)
			(layers "B.Cu" "B.Mask" "B.Paste")
			(net "P1V0")
			(options
				(clearance outline)
				(anchor circle)
			)
			(primitives
				(gr_poly
					(pts
						(arc
							(start -0.254 0.1778)
							(mid -0.239121 0.213721)
							(end -0.2032 0.2286)
						)
						(arc
							(start 0.2032 0.2286)
							(mid 0.239121 0.213721)
							(end 0.254 0.1778)
						)
						(arc
							(start 0.254 -0.1778)
							(mid 0.239121 -0.213721)
							(end 0.2032 -0.2286)
						)
						(arc
							(start -0.2032 -0.2286)
							(mid -0.239121 -0.213721)
							(end -0.254 -0.1778)
						)
					)
					(width 0)
					(fill yes)
				)
			)
		)
		(pad "2" smd custom
			(at 0 0.4572)
			(size 0.1143 0.1143)
			(layers "B.Cu" "B.Mask" "B.Paste")
			(net "GND")
			(options
				(clearance outline)
				(anchor circle)
			)
			(primitives
				(gr_poly
					(pts
						(arc
							(start -0.254 0.1778)
							(mid -0.239121 0.213721)
							(end -0.2032 0.2286)
						)
						(arc
							(start 0.2032 0.2286)
							(mid 0.239121 0.213721)
							(end 0.254 0.1778)
						)
						(arc
							(start 0.254 -0.1778)
							(mid 0.239121 -0.213721)
							(end 0.2032 -0.2286)
						)
						(arc
							(start -0.2032 -0.2286)
							(mid -0.239121 -0.213721)
							(end -0.254 -0.1778)
						)
					)
					(width 0)
					(fill yes)
				)
			)
		)
	)
	(footprint ""
		(layer "B.Cu")
		(at 103.251 -15.748 90)
		(property "Reference" "U39"
			(at 0 0 90)
			(layer "B.SilkS")
			(hide yes)
			(effects
				(font
					(size 1.27 1.27)
				)
				(justify mirror)
			)
		)
		(property "Value" "SNLVC1G126DCKR-GP"
			(at 0 -8.0772 90)
			(unlocked yes)
			(layer "B.Fab")
			(hide yes)
			(effects
				(font
					(size 1.016 1.016)
					(thickness 0.1524)
				)
				(justify mirror)
			)
		)
		(property "Device Type" "SC70-5H44"
			(at 0 -9.6012 90)
			(unlocked yes)
			(layer "B.Fab")
			(hide yes)
			(effects
				(font
					(size 1.016 1.016)
					(thickness 0.1524)
				)
				(justify mirror)
			)
		)
		(duplicate_pad_numbers_are_jumpers no)
		(fp_line
			(start 1.0033 -0.3302)
			(end -1.0033 -0.3302)
			(stroke
				(width 0.1524)
				(type default)
			)
			(layer "B.SilkS")
		)
		(fp_line
			(start -1.0033 -0.3302)
			(end -1.0033 0.3302)
			(stroke
				(width 0.1524)
				(type default)
			)
			(layer "B.SilkS")
		)
		(fp_line
			(start 1.0033 0.3302)
			(end 1.0033 -0.3302)
			(stroke
				(width 0.1524)
				(type default)
			)
			(layer "B.SilkS")
		)
		(fp_line
			(start -1.0033 0.3302)
			(end 1.0033 0.3302)
			(stroke
				(width 0.1524)
				(type default)
			)
			(layer "B.SilkS")
		)
		(fp_poly
			(pts
				(xy 1.0033 1.4859) (xy 1.0033 0.8001) (xy 1.1811 0.8001) (xy 1.1811 -0.8001) (xy 1.0033 -0.8001)
				(xy 1.0033 -1.4859) (xy -1.0033 -1.4859) (xy -1.0033 -0.8001) (xy -1.1811 -0.8001) (xy -1.1811 0.8001)
				(xy -1.0033 0.8001) (xy -1.0033 1.4859) (xy -0.2921 1.4859) (xy -0.2921 0.8001) (xy 0.2921 0.8001)
				(xy 0.2921 1.4859)
			)
			(stroke
				(width 0)
				(type default)
			)
			(fill no)
			(layer "B.CrtYd")
		)
		(fp_poly
			(pts
				(xy 1.0033 1.4859) (xy 1.0033 0.8001) (xy 1.1811 0.8001) (xy 1.1811 -0.8001) (xy 1.0033 -0.8001)
				(xy 1.0033 -1.4859) (xy -1.0033 -1.4859) (xy -1.0033 -0.8001) (xy -1.1811 -0.8001) (xy -1.1811 0.8001)
				(xy -1.0033 0.8001) (xy -1.0033 1.4859) (xy -0.2921 1.4859) (xy -0.2921 0.8001) (xy 0.2921 0.8001)
				(xy 0.2921 1.4859)
			)
			(stroke
				(width 0)
				(type default)
			)
			(fill no)
			(layer "B.Fab")
		)
		(pad "1" smd rect
			(at -0.65024 -0.93472 270)
			(size 0.3556 0.762)
			(layers "B.Cu" "B.Mask" "B.Paste")
			(net "PMU_PLTRST#")
		)
		(pad "2" smd rect
			(at 0 -0.93472 270)
			(size 0.3556 0.762)
			(layers "B.Cu" "B.Mask" "B.Paste")
			(net "IRQ_CPU_IERR#")
		)
		(pad "3" smd rect
			(at 0.65024 -0.93472 270)
			(size 0.3556 0.762)
			(layers "B.Cu" "B.Mask" "B.Paste")
			(net "GND")
		)
		(pad "4" smd rect
			(at 0.65024 0.93472 270)
			(size 0.3556 0.762)
			(layers "B.Cu" "B.Mask" "B.Paste")
			(net "IRQ_CPU_LV_IERR#")
		)
		(pad "5" smd rect
			(at -0.65024 0.93472 270)
			(size 0.3556 0.762)
			(layers "B.Cu" "B.Mask" "B.Paste")
			(net "P3V3")
		)
	)
)
